(kicad_pcb
	(version 20260206)
	(generator "pcbnew")
	(generator_version "10.0")
	(general
		(thickness 1.6)
		(legacy_teardrops no)
	)
	(paper "A4")
	(title_block
		(title "peb — Lightning_PEB_BRD.brd")
		(comment 1 "Lightning (Wiwynn / Facebook NVMe JBOF) / footprints 2491-2498 of 2563")
	)
	(layers
		(0 "F.Cu" signal "TOP")
		(4 "In1.Cu" signal "L2GND")
		(6 "In2.Cu" signal "L3")
		(8 "In3.Cu" signal "L4VCC")
		(10 "In4.Cu" signal "L5VCC")
		(12 "In5.Cu" signal "L6")
		(14 "In6.Cu" signal "L7GND")
		(2 "B.Cu" signal "BOTTOM")
		(9 "F.Adhes" user "F.Adhesive")
		(11 "B.Adhes" user "B.Adhesive")
		(13 "F.Paste" user "Package Geometry/Pastemask Top")
		(15 "B.Paste" user "Package Geometry/Pastemask Bottom")
		(5 "F.SilkS" user "Ref Des/Silkscreen Top")
		(7 "B.SilkS" user "Ref Des/Silkscreen Bottom")
		(1 "F.Mask" user "Board Geometry/Soldermask Top")
		(3 "B.Mask" user "Board Geometry/Soldermask Bottom")
		(17 "Dwgs.User" user "User.Drawings")
		(19 "Cmts.User" user "User.Comments")
		(21 "Eco1.User" user "User.Eco1")
		(23 "Eco2.User" user "User.Eco2")
		(25 "Edge.Cuts" user "Board Geometry/Outline")
		(27 "Margin" user)
		(31 "F.CrtYd" user "Package Geometry/Place Bound Top")
		(29 "B.CrtYd" user "Package Geometry/Place Bound Bottom")
		(35 "F.Fab" user "Ref Des/Assembly Top")
		(33 "B.Fab" user "Ref Des/Assembly Bottom")
	)
	(footprint ""
		(layer "B.Cu")
		(at 74.422 -189.611)
		(property "Reference" "U64"
			(at 0 0 0)
			(layer "B.SilkS")
			(hide yes)
			(effects
				(font
					(size 1.27 1.27)
				)
				(justify mirror)
			)
		)
		(property "Value" "SN74LVC1G08DCKR-GP"
			(at 2.3368 -8.6868 0)
			(unlocked yes)
			(layer "B.Fab")
			(hide yes)
			(effects
				(font
					(size 1.016 1.016)
					(thickness 0.1524)
				)
				(justify mirror)
			)
		)
		(property "Device Type" "SC70-5H44"
			(at 2.3114 -10.414 0)
			(unlocked yes)
			(layer "B.Fab")
			(hide yes)
			(effects
				(font
					(size 1.016 1.016)
					(thickness 0.1524)
				)
				(justify mirror)
			)
		)
		(duplicate_pad_numbers_are_jumpers no)
		(fp_line
			(start -1.3843 -1.8034)
			(end -1.3843 -1.1176)
			(stroke
				(width 0.3302)
				(type default)
			)
			(layer "B.SilkS")
		)
		(fp_line
			(start -1.27 -1.7018)
			(end -1.27 1.7018)
			(stroke
				(width 0.1524)
				(type default)
			)
			(layer "B.SilkS")
		)
		(fp_line
			(start -1.27 1.7018)
			(end 1.27 1.7018)
			(stroke
				(width 0.1524)
				(type default)
			)
			(layer "B.SilkS")
		)
		(fp_line
			(start -0.6604 -1.8034)
			(end -1.3843 -1.8034)
			(stroke
				(width 0.3302)
				(type default)
			)
			(layer "B.SilkS")
		)
		(fp_line
			(start 1.27 -1.7018)
			(end -1.27 -1.7018)
			(stroke
				(width 0.1524)
				(type default)
			)
			(layer "B.SilkS")
		)
		(fp_line
			(start 1.27 1.7018)
			(end 1.27 -1.7018)
			(stroke
				(width 0.1524)
				(type default)
			)
			(layer "B.SilkS")
		)
		(fp_rect
			(start 1.524 1.9558)
			(end -1.524 -1.9558)
			(stroke
				(width 0)
				(type default)
			)
			(fill no)
			(layer "B.CrtYd")
		)
		(fp_poly
			(pts
				(xy 1.524 -1.9558) (xy -1.524 -1.9558) (xy -1.524 1.9558) (xy 1.524 1.9558)
			)
			(stroke
				(width 0)
				(type default)
			)
			(fill no)
			(layer "B.Fab")
		)
		(pad "1" smd rect
			(at -0.65024 -0.8255 180)
			(size 0.4064 1.2192)
			(layers "B.Cu" "B.Mask" "B.Paste")
			(net "BMC_SSD_RST#0_A0")
		)
		(pad "2" smd rect
			(at 0 -0.8255 180)
			(size 0.4064 1.2192)
			(layers "B.Cu" "B.Mask" "B.Paste")
			(net "SSD_PERST#0_B0")
		)
		(pad "3" smd rect
			(at 0.65024 -0.8255 180)
			(size 0.4064 1.2192)
			(layers "B.Cu" "B.Mask" "B.Paste")
			(net "GND")
		)
		(pad "4" smd rect
			(at 0.65024 0.8255 180)
			(size 0.4064 1.2192)
			(layers "B.Cu" "B.Mask" "B.Paste")
			(net "SSD_PERST_Y0")
		)
		(pad "5" smd rect
			(at -0.65024 0.8255 180)
			(size 0.4064 1.2192)
			(layers "B.Cu" "B.Mask" "B.Paste")
			(net "P3V3_STBY")
		)
	)
	(footprint ""
		(layer "B.Cu")
		(at 219.806012 -203.055474)
		(property "Reference" "R551"
			(at 0 0 0)
			(layer "B.SilkS")
			(hide yes)
			(effects
				(font
					(size 1.27 1.27)
				)
				(justify mirror)
			)
		)
		(property "Value" "10KR2F-2-GP"
			(at -0.064008 -3.993896 0)
			(unlocked yes)
			(layer "B.Fab")
			(hide yes)
			(effects
				(font
					(size 1.016 1.016)
					(thickness 0.1524)
				)
				(justify mirror)
			)
		)
		(property "Device Type" "R402H16"
			(at -0.064008 -5.517896 0)
			(unlocked yes)
			(layer "B.Fab")
			(hide yes)
			(effects
				(font
					(size 1.016 1.016)
					(thickness 0.1524)
				)
				(justify mirror)
			)
		)
		(duplicate_pad_numbers_are_jumpers no)
		(fp_line
			(start -0.508 -0.9398)
			(end 0.508 -0.9398)
			(stroke
				(width 0.1524)
				(type default)
			)
			(layer "B.SilkS")
		)
		(fp_line
			(start 0.508 -0.9398)
			(end 0.508 0.9398)
			(stroke
				(width 0.1524)
				(type default)
			)
			(layer "B.SilkS")
		)
		(fp_rect
			(start 0.508 0.9398)
			(end -0.508 -0.9398)
			(stroke
				(width 0)
				(type default)
			)
			(fill no)
			(layer "B.CrtYd")
		)
		(fp_rect
			(start 0.508 0.9398)
			(end -0.508 -0.9398)
			(stroke
				(width 0)
				(type default)
			)
			(fill no)
			(layer "B.Fab")
		)
		(pad "1" smd custom
			(at 0 -0.4445 180)
			(size 0.1397 0.1397)
			(layers "B.Cu" "B.Mask" "B.Paste")
			(net "P3V3_STBY")
			(options
				(clearance outline)
				(anchor circle)
			)
			(primitives
				(gr_poly
					(pts
						(arc
							(start -0.1778 0.2794)
							(mid -0.249642 0.249642)
							(end -0.2794 0.1778)
						)
						(arc
							(start -0.2794 -0.1778)
							(mid -0.249642 -0.249642)
							(end -0.1778 -0.2794)
						)
						(arc
							(start 0.1778 -0.2794)
							(mid 0.249642 -0.249642)
							(end 0.2794 -0.1778)
						)
						(arc
							(start 0.2794 0.1778)
							(mid 0.249642 0.249642)
							(end 0.1778 0.2794)
						)
					)
					(width 0)
					(fill yes)
				)
			)
		)
		(pad "2" smd custom
			(at 0 0.4445 180)
			(size 0.1397 0.1397)
			(layers "B.Cu" "B.Mask" "B.Paste")
			(net "IOEXP3_AD0")
			(options
				(clearance outline)
				(anchor circle)
			)
			(primitives
				(gr_poly
					(pts
						(arc
							(start -0.1778 0.2794)
							(mid -0.249642 0.249642)
							(end -0.2794 0.1778)
						)
						(arc
							(start -0.2794 -0.1778)
							(mid -0.249642 -0.249642)
							(end -0.1778 -0.2794)
						)
						(arc
							(start 0.1778 -0.2794)
							(mid 0.249642 -0.249642)
							(end 0.2794 -0.1778)
						)
						(arc
							(start 0.2794 0.1778)
							(mid 0.249642 0.249642)
							(end 0.1778 0.2794)
						)
					)
					(width 0)
					(fill yes)
				)
			)
		)
	)
	(footprint ""
		(layer "B.Cu")
		(at 267.5128 -9.30021 90)
		(property "Reference" "R725"
			(at 0 0 90)
			(layer "B.SilkS")
			(hide yes)
			(effects
				(font
					(size 1.27 1.27)
				)
				(justify mirror)
			)
		)
		(property "Value" "0R2J-2-GP"
			(at -0.064008 -3.993896 90)
			(unlocked yes)
			(layer "B.Fab")
			(hide yes)
			(effects
				(font
					(size 1.016 1.016)
					(thickness 0.1524)
				)
				(justify mirror)
			)
		)
		(property "Device Type" "R402H16"
			(at -0.064008 -5.517896 90)
			(unlocked yes)
			(layer "B.Fab")
			(hide yes)
			(effects
				(font
					(size 1.016 1.016)
					(thickness 0.1524)
				)
				(justify mirror)
			)
		)
		(duplicate_pad_numbers_are_jumpers no)
		(fp_line
			(start 0.508 -0.9398)
			(end 0.508 0.9398)
			(stroke
				(width 0.1524)
				(type default)
			)
			(layer "B.SilkS")
		)
		(fp_line
			(start -0.508 -0.9398)
			(end 0.508 -0.9398)
			(stroke
				(width 0.1524)
				(type default)
			)
			(layer "B.SilkS")
		)
		(fp_rect
			(start 0.508 0.9398)
			(end -0.508 -0.9398)
			(stroke
				(width 0)
				(type default)
			)
			(fill no)
			(layer "B.CrtYd")
		)
		(fp_rect
			(start 0.508 0.9398)
			(end -0.508 -0.9398)
			(stroke
				(width 0)
				(type default)
			)
			(fill no)
			(layer "B.Fab")
		)
		(pad "1" smd custom
			(at 0 -0.4445 270)
			(size 0.1397 0.1397)
			(layers "B.Cu" "B.Mask" "B.Paste")
			(net "HOST8_RST_N_C")
			(options
				(clearance outline)
				(anchor circle)
			)
			(primitives
				(gr_poly
					(pts
						(arc
							(start -0.1778 0.2794)
							(mid -0.249642 0.249642)
							(end -0.2794 0.1778)
						)
						(arc
							(start -0.2794 -0.1778)
							(mid -0.249642 -0.249642)
							(end -0.1778 -0.2794)
						)
						(arc
							(start 0.1778 -0.2794)
							(mid 0.249642 -0.249642)
							(end 0.2794 -0.1778)
						)
						(arc
							(start 0.2794 0.1778)
							(mid 0.249642 0.249642)
							(end 0.1778 0.2794)
						)
					)
					(width 0)
					(fill yes)
				)
			)
		)
		(pad "2" smd custom
			(at 0 0.4445 270)
			(size 0.1397 0.1397)
			(layers "B.Cu" "B.Mask" "B.Paste")
			(net "P3V3_STBY")
			(options
				(clearance outline)
				(anchor circle)
			)
			(primitives
				(gr_poly
					(pts
						(arc
							(start -0.1778 0.2794)
							(mid -0.249642 0.249642)
							(end -0.2794 0.1778)
						)
						(arc
							(start -0.2794 -0.1778)
							(mid -0.249642 -0.249642)
							(end -0.1778 -0.2794)
						)
						(arc
							(start 0.1778 -0.2794)
							(mid 0.249642 -0.249642)
							(end 0.2794 -0.1778)
						)
						(arc
							(start 0.2794 0.1778)
							(mid 0.249642 0.249642)
							(end 0.1778 0.2794)
						)
					)
					(width 0)
					(fill yes)
				)
			)
		)
	)
	(footprint ""
		(layer "B.Cu")
		(at 41.656 -129.286 -90)
		(property "Reference" "C208"
			(at 0 0 90)
			(layer "B.SilkS")
			(hide yes)
			(effects
				(font
					(size 1.27 1.27)
				)
				(justify mirror)
			)
		)
		(property "Value" "SC1U10V2KX-4-GP"
			(at -1.1811 -2.7051 270)
			(unlocked yes)
			(layer "B.Fab")
			(hide yes)
			(effects
				(font
					(size 1.016 1.016)
					(thickness 0.1524)
				)
				(justify mirror)
			)
		)
		(property "Device Type" "C402H22"
			(at -1.1811 -4.2291 270)
			(unlocked yes)
			(layer "B.Fab")
			(hide yes)
			(effects
				(font
					(size 1.016 1.016)
					(thickness 0.1524)
				)
				(justify mirror)
			)
		)
		(duplicate_pad_numbers_are_jumpers no)
		(fp_rect
			(start 0.4318 0.9525)
			(end -0.4318 -0.9525)
			(stroke
				(width 0)
				(type default)
			)
			(fill no)
			(layer "B.CrtYd")
		)
		(fp_rect
			(start 0.4318 0.9525)
			(end -0.4318 -0.9525)
			(stroke
				(width 0)
				(type default)
			)
			(fill no)
			(layer "B.Fab")
		)
		(pad "1" smd custom
			(at 0 -0.4445 90)
			(size 0.1524 0.1524)
			(layers "B.Cu" "B.Mask" "B.Paste")
			(net "P3V3_STBY")
			(options
				(clearance outline)
				(anchor circle)
			)
			(primitives
				(gr_poly
					(pts
						(arc
							(start 0.3048 0.2032)
							(mid 0.275042 0.275042)
							(end 0.2032 0.3048)
						)
						(arc
							(start -0.2032 0.3048)
							(mid -0.275042 0.275042)
							(end -0.3048 0.2032)
						)
						(arc
							(start -0.3048 -0.2032)
							(mid -0.275042 -0.275042)
							(end -0.2032 -0.3048)
						)
						(arc
							(start 0.2032 -0.3048)
							(mid 0.275042 -0.275042)
							(end 0.3048 -0.2032)
						)
					)
					(width 0)
					(fill yes)
				)
			)
		)
		(pad "2" smd custom
			(at 0 0.4445 90)
			(size 0.1524 0.1524)
			(layers "B.Cu" "B.Mask" "B.Paste")
			(net "GND")
			(options
				(clearance outline)
				(anchor circle)
			)
			(primitives
				(gr_poly
					(pts
						(arc
							(start 0.3048 0.2032)
							(mid 0.275042 0.275042)
							(end 0.2032 0.3048)
						)
						(arc
							(start -0.2032 0.3048)
							(mid -0.275042 0.275042)
							(end -0.3048 0.2032)
						)
						(arc
							(start -0.3048 -0.2032)
							(mid -0.275042 -0.275042)
							(end -0.2032 -0.3048)
						)
						(arc
							(start 0.2032 -0.3048)
							(mid 0.275042 -0.275042)
							(end 0.3048 -0.2032)
						)
					)
					(width 0)
					(fill yes)
				)
			)
		)
	)
	(footprint ""
		(layer "B.Cu")
		(at 227.629212 -200.007474)
		(property "Reference" "R3237"
			(at 0 0 0)
			(layer "B.SilkS")
			(hide yes)
			(effects
				(font
					(size 1.27 1.27)
				)
				(justify mirror)
			)
		)
		(property "Value" "0R2J-2-GP"
			(at -0.064008 -3.993896 0)
			(unlocked yes)
			(layer "B.Fab")
			(hide yes)
			(effects
				(font
					(size 1.016 1.016)
					(thickness 0.1524)
				)
				(justify mirror)
			)
		)
		(property "Device Type" "R402H16"
			(at -0.064008 -5.517896 0)
			(unlocked yes)
			(layer "B.Fab")
			(hide yes)
			(effects
				(font
					(size 1.016 1.016)
					(thickness 0.1524)
				)
				(justify mirror)
			)
		)
		(duplicate_pad_numbers_are_jumpers no)
		(fp_line
			(start -0.508 -0.9398)
			(end 0.508 -0.9398)
			(stroke
				(width 0.1524)
				(type default)
			)
			(layer "B.SilkS")
		)
		(fp_line
			(start 0.508 -0.9398)
			(end 0.508 0.9398)
			(stroke
				(width 0.1524)
				(type default)
			)
			(layer "B.SilkS")
		)
		(fp_rect
			(start 0.508 0.9398)
			(end -0.508 -0.9398)
			(stroke
				(width 0)
				(type default)
			)
			(fill no)
			(layer "B.CrtYd")
		)
		(fp_rect
			(start 0.508 0.9398)
			(end -0.508 -0.9398)
			(stroke
				(width 0)
				(type default)
			)
			(fill no)
			(layer "B.Fab")
		)
		(pad "1" smd custom
			(at 0 -0.4445 180)
			(size 0.1397 0.1397)
			(layers "B.Cu" "B.Mask" "B.Paste")
			(net "SSD_PERST#12")
			(options
				(clearance outline)
				(anchor circle)
			)
			(primitives
				(gr_poly
					(pts
						(arc
							(start -0.1778 0.2794)
							(mid -0.249642 0.249642)
							(end -0.2794 0.1778)
						)
						(arc
							(start -0.2794 -0.1778)
							(mid -0.249642 -0.249642)
							(end -0.1778 -0.2794)
						)
						(arc
							(start 0.1778 -0.2794)
							(mid 0.249642 -0.249642)
							(end 0.2794 -0.1778)
						)
						(arc
							(start 0.2794 0.1778)
							(mid 0.249642 0.249642)
							(end 0.1778 0.2794)
						)
					)
					(width 0)
					(fill yes)
				)
			)
		)
		(pad "2" smd custom
			(at 0 0.4445 180)
			(size 0.1397 0.1397)
			(layers "B.Cu" "B.Mask" "B.Paste")
			(net "SSD_PERST#0_B12")
			(options
				(clearance outline)
				(anchor circle)
			)
			(primitives
				(gr_poly
					(pts
						(arc
							(start -0.1778 0.2794)
							(mid -0.249642 0.249642)
							(end -0.2794 0.1778)
						)
						(arc
							(start -0.2794 -0.1778)
							(mid -0.249642 -0.249642)
							(end -0.1778 -0.2794)
						)
						(arc
							(start 0.1778 -0.2794)
							(mid 0.249642 -0.249642)
							(end 0.2794 -0.1778)
						)
						(arc
							(start 0.2794 0.1778)
							(mid 0.249642 0.249642)
							(end 0.1778 0.2794)
						)
					)
					(width 0)
					(fill yes)
				)
			)
		)
	)
	(footprint ""
		(layer "B.Cu")
		(at 247.591072 -32.004)
		(property "Reference" "C471"
			(at 0 0 0)
			(layer "B.SilkS")
			(hide yes)
			(effects
				(font
					(size 1.27 1.27)
				)
				(justify mirror)
			)
		)
		(property "Value" "SCD1U16V1KX-1-GP"
			(at 2.8321 -1.7399 0)
			(unlocked yes)
			(layer "B.Fab")
			(hide yes)
			(effects
				(font
					(size 1.016 1.016)
					(thickness 0.1524)
				)
				(justify mirror)
			)
		)
		(property "Device Type" "C0201H13"
			(at 2.8321 -3.2639 0)
			(unlocked yes)
			(layer "B.Fab")
			(hide yes)
			(effects
				(font
					(size 1.016 1.016)
					(thickness 0.1524)
				)
				(justify mirror)
			)
		)
		(duplicate_pad_numbers_are_jumpers no)
		(fp_rect
			(start 0.2794 0.6477)
			(end -0.2794 -0.6477)
			(stroke
				(width 0)
				(type default)
			)
			(fill no)
			(layer "B.CrtYd")
		)
		(fp_rect
			(start 0.2794 0.6477)
			(end -0.2794 -0.6477)
			(stroke
				(width 0)
				(type default)
			)
			(fill no)
			(layer "B.Fab")
		)
		(pad "1" smd custom
			(at 0 -0.2794 180)
			(size 0.0762 0.0762)
			(layers "B.Cu" "B.Mask" "B.Paste")
			(net "DUT_VDDO")
			(options
				(clearance outline)
				(anchor circle)
			)
			(primitives
				(gr_poly
					(pts
						(arc
							(start 0.1524 0.127)
							(mid 0.137521 0.162921)
							(end 0.1016 0.1778)
						)
						(arc
							(start -0.1016 0.1778)
							(mid -0.137521 0.162921)
							(end -0.1524 0.127)
						)
						(arc
							(start -0.1524 -0.127)
							(mid -0.137521 -0.162921)
							(end -0.1016 -0.1778)
						)
						(arc
							(start 0.1016 -0.1778)
							(mid 0.137521 -0.162921)
							(end 0.1524 -0.127)
						)
					)
					(width 0)
					(fill yes)
				)
			)
		)
		(pad "2" smd custom
			(at 0 0.2794 180)
			(size 0.0762 0.0762)
			(layers "B.Cu" "B.Mask" "B.Paste")
			(net "GND")
			(options
				(clearance outline)
				(anchor circle)
			)
			(primitives
				(gr_poly
					(pts
						(arc
							(start 0.1524 0.127)
							(mid 0.137521 0.162921)
							(end 0.1016 0.1778)
						)
						(arc
							(start -0.1016 0.1778)
							(mid -0.137521 0.162921)
							(end -0.1524 0.127)
						)
						(arc
							(start -0.1524 -0.127)
							(mid -0.137521 -0.162921)
							(end -0.1016 -0.1778)
						)
						(arc
							(start 0.1016 -0.1778)
							(mid 0.137521 -0.162921)
							(end 0.1524 -0.127)
						)
					)
					(width 0)
					(fill yes)
				)
			)
		)
	)
	(footprint ""
		(layer "B.Cu")
		(at 296.724578 -35.058604 180)
		(property "Reference" "C257"
			(at 0 0 0)
			(layer "B.SilkS")
			(hide yes)
			(effects
				(font
					(size 1.27 1.27)
				)
				(justify mirror)
			)
		)
		(property "Value" "SCD1U10V2KX-5GP"
			(at -1.1811 -2.7051 180)
			(unlocked yes)
			(layer "B.Fab")
			(hide yes)
			(effects
				(font
					(size 1.016 1.016)
					(thickness 0.1524)
				)
				(justify mirror)
			)
		)
		(property "Device Type" "C402H22"
			(at -1.1811 -4.2291 180)
			(unlocked yes)
			(layer "B.Fab")
			(hide yes)
			(effects
				(font
					(size 1.016 1.016)
					(thickness 0.1524)
				)
				(justify mirror)
			)
		)
		(duplicate_pad_numbers_are_jumpers no)
		(fp_rect
			(start 0.4318 0.9525)
			(end -0.4318 -0.9525)
			(stroke
				(width 0)
				(type default)
			)
			(fill no)
			(layer "B.CrtYd")
		)
		(fp_rect
			(start 0.4318 0.9525)
			(end -0.4318 -0.9525)
			(stroke
				(width 0)
				(type default)
			)
			(fill no)
			(layer "B.Fab")
		)
		(pad "1" smd custom
			(at 0 -0.4445)
			(size 0.1524 0.1524)
			(layers "B.Cu" "B.Mask" "B.Paste")
			(net "GND")
			(options
				(clearance outline)
				(anchor circle)
			)
			(primitives
				(gr_poly
					(pts
						(arc
							(start 0.3048 0.2032)
							(mid 0.275042 0.275042)
							(end 0.2032 0.3048)
						)
						(arc
							(start -0.2032 0.3048)
							(mid -0.275042 0.275042)
							(end -0.3048 0.2032)
						)
						(arc
							(start -0.3048 -0.2032)
							(mid -0.275042 -0.275042)
							(end -0.2032 -0.3048)
						)
						(arc
							(start 0.2032 -0.3048)
							(mid 0.275042 -0.275042)
							(end 0.3048 -0.2032)
						)
					)
					(width 0)
					(fill yes)
				)
			)
		)
		(pad "2" smd custom
			(at 0 0.4445)
			(size 0.1524 0.1524)
			(layers "B.Cu" "B.Mask" "B.Paste")
			(net "P3V3_STBY")
			(options
				(clearance outline)
				(anchor circle)
			)
			(primitives
				(gr_poly
					(pts
						(arc
							(start 0.3048 0.2032)
							(mid 0.275042 0.275042)
							(end 0.2032 0.3048)
						)
						(arc
							(start -0.2032 0.3048)
							(mid -0.275042 0.275042)
							(end -0.3048 0.2032)
						)
						(arc
							(start -0.3048 -0.2032)
							(mid -0.275042 -0.275042)
							(end -0.2032 -0.3048)
						)
						(arc
							(start 0.2032 -0.3048)
							(mid 0.275042 -0.275042)
							(end 0.3048 -0.2032)
						)
					)
					(width 0)
					(fill yes)
				)
			)
		)
	)
	(footprint ""
		(layer "B.Cu")
		(at 243.967 -26.67 90)
		(property "Reference" "TP197"
			(at 0 0 90)
			(layer "B.SilkS")
			(hide yes)
			(effects
				(font
					(size 1.27 1.27)
				)
				(justify mirror)
			)
		)
		(property "Value" "TPAD28-2-GP"
			(at 0.0127 -1.6637 90)
			(unlocked yes)
			(layer "B.Fab")
			(hide yes)
			(effects
				(font
					(size 1.016 1.016)
					(thickness 0.1524)
				)
				(justify mirror)
			)
		)
		(property "Device Type" "TPAD28"
			(at 0.0127 -3.1877 90)
			(unlocked yes)
			(layer "B.Fab")
			(hide yes)
			(effects
				(font
					(size 1.016 1.016)
					(thickness 0.1524)
				)
				(justify mirror)
			)
		)
		(duplicate_pad_numbers_are_jumpers no)
		(fp_poly
			(pts
				(arc
					(start 0 0.3556)
					(mid 0 -0.3556)
					(end 0 0.3556)
				)
			)
			(stroke
				(width 0)
				(type default)
			)
			(fill no)
			(layer "B.CrtYd")
		)
		(fp_poly
			(pts
				(arc
					(start 0 0.6096)
					(mid 0 -0.6096)
					(end 0 0.6096)
				)
			)
			(stroke
				(width 0)
				(type default)
			)
			(fill no)
			(layer "B.Fab")
		)
		(pad "1" smd circle
			(at 0 0 270)
			(size 0.7112 0.7112)
			(layers "B.Cu" "B.Mask" "B.Paste")
			(net "LBI_CE#3")
		)
	)
)
